# T6G (Grand Teton) — schematic netlist excerpt (pin names and nets, part order shuffled) for the footprints in the layout excerpt that follows; sources: Cadence DE-HDL packaged netlist, KiCad conversion of 04192023_DAF0TMB3IC0_F0TG_MB_C_brd_V02_OCP.brd

R1302  Q_RES  10 1% CHIP  pkg 0402LF  page 357 : A = P12V_OCP_V3_2_R ; B = VSENSE_P12V_INA230_7_INN
R1294  Q_RES  0 5% CHIP  pkg 0402LF  page 159 : A = I3C_SPD_DDRAF_CPU1_SDA ; B = I3C_SPD_DDRAF_CPU1_LVC1_SDA

(kicad_pcb
	(version 20260206)
	(generator "pcbnew")
	(generator_version "10.0")
	(general
		(thickness 1.6)
		(legacy_teardrops no)
	)
	(paper "A4")
	(title_block
		(title "04192023_DAF0TMB3IC0_F0TG_MB_C_brd_V02_OCP.brd")
		(comment 1 "Grand Teton / footprints 867-868 of 8354")
	)
	(layers
		(0 "F.Cu" signal "TOP")
		(4 "In1.Cu" signal "GND")
		(6 "In2.Cu" signal "IN1")
		(8 "In3.Cu" signal "GND1")
		(10 "In4.Cu" signal "IN2")
		(12 "In5.Cu" signal "GND2")
		(14 "In6.Cu" signal "IN3")
		(16 "In7.Cu" signal "GND3")
		(18 "In8.Cu" signal "VCC")
		(20 "In9.Cu" signal "VCC1")
		(22 "In10.Cu" signal "GND4")
		(24 "In11.Cu" signal "IN4")
		(26 "In12.Cu" signal "GND5")
		(28 "In13.Cu" signal "IN5")
		(30 "In14.Cu" signal "GND6")
		(32 "In15.Cu" signal "IN6")
		(34 "In16.Cu" signal "GND7")
		(2 "B.Cu" signal "BOTTOM")
		(9 "F.Adhes" user "F.Adhesive")
		(11 "B.Adhes" user "B.Adhesive")
		(13 "F.Paste" user "Package Geometry/Pastemask Top")
		(15 "B.Paste" user "Package Geometry/Pastemask Bottom")
		(5 "F.SilkS" user "Ref Des/Silkscreen Top")
		(7 "B.SilkS" user "Ref Des/Silkscreen Bottom")
		(1 "F.Mask" user "Board Geometry/Soldermask Top")
		(3 "B.Mask" user "Board Geometry/Soldermask Bottom")
		(17 "Dwgs.User" user "User.Drawings")
		(19 "Cmts.User" user "User.Comments")
		(21 "Eco1.User" user "User.Eco1")
		(23 "Eco2.User" user "User.Eco2")
		(25 "Edge.Cuts" user "Board Geometry/Outline")
		(27 "Margin" user)
		(31 "F.CrtYd" user "Package Geometry/Place Bound Top")
		(29 "B.CrtYd" user "Package Geometry/Place Bound Bottom")
		(35 "F.Fab" user "Ref Des/Assembly Top")
		(33 "B.Fab" user "Ref Des/Assembly Bottom")
	)
	(footprint ""
		(layer "F.Cu")
		(at 34.665158 -173.55566)
		(property "Reference" "R1294"
			(at 0 0 0)
			(layer "F.SilkS")
			(hide yes)
			(effects
				(font
					(size 1.27 1.27)
				)
			)
		)
		(property "Value" ""
			(at 0 0 0)
			(layer "F.Fab")
			(effects
				(font
					(size 1.27 1.27)
				)
			)
		)
		(duplicate_pad_numbers_are_jumpers no)
		(fp_line
			(start -0.7874 -0.4064)
			(end 0.7874 -0.4064)
			(stroke
				(width 0.1524)
				(type default)
			)
			(layer "F.SilkS")
		)
		(fp_line
			(start -0.7874 0.4064)
			(end -0.7874 -0.4064)
			(stroke
				(width 0.1524)
				(type default)
			)
			(layer "F.SilkS")
		)
		(fp_line
			(start 0.7874 -0.4064)
			(end 0.7874 0.4064)
			(stroke
				(width 0.1524)
				(type default)
			)
			(layer "F.SilkS")
		)
		(fp_line
			(start 0.7874 0.4064)
			(end -0.7874 0.4064)
			(stroke
				(width 0.1524)
				(type default)
			)
			(layer "F.SilkS")
		)
		(fp_line
			(start -0.67945 -0.305054)
			(end -0.12065 -0.305054)
			(stroke
				(width 0.1)
				(type default)
			)
			(layer "F.Fab")
		)
		(fp_line
			(start -0.67945 0.3048)
			(end -0.67945 -0.305054)
			(stroke
				(width 0.1)
				(type default)
			)
			(layer "F.Fab")
		)
		(fp_line
			(start -0.12065 -0.305054)
			(end -0.12065 -0.2794)
			(stroke
				(width 0.1)
				(type default)
			)
			(layer "F.Fab")
		)
		(fp_line
			(start -0.12065 -0.2794)
			(end 0.12065 -0.2794)
			(stroke
				(width 0.1)
				(type default)
			)
			(layer "F.Fab")
		)
		(fp_line
			(start -0.12065 0.2794)
			(end -0.12065 0.3048)
			(stroke
				(width 0.1)
				(type default)
			)
			(layer "F.Fab")
		)
		(fp_line
			(start -0.12065 0.3048)
			(end -0.67945 0.3048)
			(stroke
				(width 0.1)
				(type default)
			)
			(layer "F.Fab")
		)
		(fp_line
			(start 0.120396 0.2794)
			(end -0.12065 0.2794)
			(stroke
				(width 0.1)
				(type default)
			)
			(layer "F.Fab")
		)
		(fp_line
			(start 0.120396 0.3048)
			(end 0.120396 0.2794)
			(stroke
				(width 0.1)
				(type default)
			)
			(layer "F.Fab")
		)
		(fp_line
			(start 0.12065 -0.3048)
			(end 0.67945 -0.3048)
			(stroke
				(width 0.1)
				(type default)
			)
			(layer "F.Fab")
		)
		(fp_line
			(start 0.12065 -0.2794)
			(end 0.12065 -0.3048)
			(stroke
				(width 0.1)
				(type default)
			)
			(layer "F.Fab")
		)
		(fp_line
			(start 0.67945 -0.3048)
			(end 0.67945 0.3048)
			(stroke
				(width 0.1)
				(type default)
			)
			(layer "F.Fab")
		)
		(fp_line
			(start 0.67945 0.3048)
			(end 0.120396 0.3048)
			(stroke
				(width 0.1)
				(type default)
			)
			(layer "F.Fab")
		)
		(pad "1" smd rect
			(at -0.40005 0 180)
			(size 0.4572 0.508)
			(layers "F.Cu" "F.Mask" "F.Paste")
			(net "I3C_SPD_DDRAF_CPU1_SDA")
		)
		(pad "2" smd rect
			(at 0.40005 0 180)
			(size 0.4572 0.508)
			(layers "F.Cu" "F.Mask" "F.Paste")
			(net "I3C_SPD_DDRAF_CPU1_LVC1_SDA")
		)
	)
	(footprint ""
		(layer "F.Cu")
		(at 69.457824 -18.932144)
		(property "Reference" "R1302"
			(at 0 0 0)
			(layer "F.SilkS")
			(hide yes)
			(effects
				(font
					(size 1.27 1.27)
				)
			)
		)
		(property "Value" ""
			(at 0 0 0)
			(layer "F.Fab")
			(effects
				(font
					(size 1.27 1.27)
				)
			)
		)
		(duplicate_pad_numbers_are_jumpers no)
		(fp_line
			(start -0.7874 -0.4064)
			(end 0.7874 -0.4064)
			(stroke
				(width 0.1524)
				(type default)
			)
			(layer "F.SilkS")
		)
		(fp_line
			(start -0.7874 0.4064)
			(end -0.7874 -0.4064)
			(stroke
				(width 0.1524)
				(type default)
			)
			(layer "F.SilkS")
		)
		(fp_line
			(start 0.7874 -0.4064)
			(end 0.7874 0.4064)
			(stroke
				(width 0.1524)
				(type default)
			)
			(layer "F.SilkS")
		)
		(fp_line
			(start 0.7874 0.4064)
			(end -0.7874 0.4064)
			(stroke
				(width 0.1524)
				(type default)
			)
			(layer "F.SilkS")
		)
		(fp_line
			(start -0.67945 -0.305054)
			(end -0.12065 -0.305054)
			(stroke
				(width 0.1)
				(type default)
			)
			(layer "F.Fab")
		)
		(fp_line
			(start -0.67945 0.3048)
			(end -0.67945 -0.305054)
			(stroke
				(width 0.1)
				(type default)
			)
			(layer "F.Fab")
		)
		(fp_line
			(start -0.12065 -0.305054)
			(end -0.12065 -0.2794)
			(stroke
				(width 0.1)
				(type default)
			)
			(layer "F.Fab")
		)
		(fp_line
			(start -0.12065 -0.2794)
			(end 0.12065 -0.2794)
			(stroke
				(width 0.1)
				(type default)
			)
			(layer "F.Fab")
		)
		(fp_line
			(start -0.12065 0.2794)
			(end -0.12065 0.3048)
			(stroke
				(width 0.1)
				(type default)
			)
			(layer "F.Fab")
		)
		(fp_line
			(start -0.12065 0.3048)
			(end -0.67945 0.3048)
			(stroke
				(width 0.1)
				(type default)
			)
			(layer "F.Fab")
		)
		(fp_line
			(start 0.120396 0.2794)
			(end -0.12065 0.2794)
			(stroke
				(width 0.1)
				(type default)
			)
			(layer "F.Fab")
		)
		(fp_line
			(start 0.120396 0.3048)
			(end 0.120396 0.2794)
			(stroke
				(width 0.1)
				(type default)
			)
			(layer "F.Fab")
		)
		(fp_line
			(start 0.12065 -0.3048)
			(end 0.67945 -0.3048)
			(stroke
				(width 0.1)
				(type default)
			)
			(layer "F.Fab")
		)
		(fp_line
			(start 0.12065 -0.2794)
			(end 0.12065 -0.3048)
			(stroke
				(width 0.1)
				(type default)
			)
			(layer "F.Fab")
		)
		(fp_line
			(start 0.67945 -0.3048)
			(end 0.67945 0.3048)
			(stroke
				(width 0.1)
				(type default)
			)
			(layer "F.Fab")
		)
		(fp_line
			(start 0.67945 0.3048)
			(end 0.120396 0.3048)
			(stroke
				(width 0.1)
				(type default)
			)
			(layer "F.Fab")
		)
		(pad "1" smd circle
			(at -0.40005 0)
			(size 0 0)
			(layers "F.Cu" "F.Mask" "F.Paste")
			(net "P12V_OCP_V3_2_R")
		)
		(pad "2" smd circle
			(at 0.40005 0)
			(size 0 0)
			(layers "F.Cu" "F.Mask" "F.Paste")
			(net "VSENSE_P12V_INA230_7_INN")
		)
	)
)
